# T6G (Grand Teton) — schematic netlist excerpt (pin names and nets, part order shuffled) for the footprints in the layout excerpt that follows; sources: Cadence DE-HDL packaged netlist, KiCad conversion of 04192023_DAF0TMB3IC0_F0TG_MB_C_brd_V02_OCP.brd

R6024  Q_RES  4.7K 5% EMPTY  pkg 0402LF  page 151 : A = P3V3_AUX ; B = SGPIO_SCM_INTR_N
R1369  Q_RES  1K 1% EMPTY  pkg 0201LF  page 276 : A = P1V8_CPU0_RT_1D ; B = RXDET_BYP_RT_CPU0_P0
PR40  Q_RES  0 5% CHIP  pkg 0402LF  page 200 : A = SVID_PVDDCR_CPU1_P0_SVTI ; B = GND

(kicad_pcb
	(version 20260206)
	(generator "pcbnew")
	(generator_version "10.0")
	(general
		(thickness 1.6)
		(legacy_teardrops no)
	)
	(paper "A4")
	(title_block
		(title "04192023_DAF0TMB3IC0_F0TG_MB_C_brd_V02_OCP.brd")
		(comment 1 "Grand Teton / footprints 4853-4855 of 8354")
	)
	(layers
		(0 "F.Cu" signal "TOP")
		(4 "In1.Cu" signal "GND")
		(6 "In2.Cu" signal "IN1")
		(8 "In3.Cu" signal "GND1")
		(10 "In4.Cu" signal "IN2")
		(12 "In5.Cu" signal "GND2")
		(14 "In6.Cu" signal "IN3")
		(16 "In7.Cu" signal "GND3")
		(18 "In8.Cu" signal "VCC")
		(20 "In9.Cu" signal "VCC1")
		(22 "In10.Cu" signal "GND4")
		(24 "In11.Cu" signal "IN4")
		(26 "In12.Cu" signal "GND5")
		(28 "In13.Cu" signal "IN5")
		(30 "In14.Cu" signal "GND6")
		(32 "In15.Cu" signal "IN6")
		(34 "In16.Cu" signal "GND7")
		(2 "B.Cu" signal "BOTTOM")
		(9 "F.Adhes" user "F.Adhesive")
		(11 "B.Adhes" user "B.Adhesive")
		(13 "F.Paste" user "Package Geometry/Pastemask Top")
		(15 "B.Paste" user "Package Geometry/Pastemask Bottom")
		(5 "F.SilkS" user "Ref Des/Silkscreen Top")
		(7 "B.SilkS" user "Ref Des/Silkscreen Bottom")
		(1 "F.Mask" user "Board Geometry/Soldermask Top")
		(3 "B.Mask" user "Board Geometry/Soldermask Bottom")
		(17 "Dwgs.User" user "User.Drawings")
		(19 "Cmts.User" user "User.Comments")
		(21 "Eco1.User" user "User.Eco1")
		(23 "Eco2.User" user "User.Eco2")
		(25 "Edge.Cuts" user "Board Geometry/Outline")
		(27 "Margin" user)
		(31 "F.CrtYd" user "Package Geometry/Place Bound Top")
		(29 "B.CrtYd" user "Package Geometry/Place Bound Bottom")
		(35 "F.Fab" user "Ref Des/Assembly Top")
		(33 "B.Fab" user "Ref Des/Assembly Bottom")
	)
	(footprint ""
		(layer "F.Cu")
		(at 149.990048 -26.68778 -90)
		(property "Reference" "R6024"
			(at 0 0 270)
			(layer "F.SilkS")
			(hide yes)
			(effects
				(font
					(size 1.27 1.27)
				)
			)
		)
		(property "Value" ""
			(at 0 0 270)
			(layer "F.Fab")
			(effects
				(font
					(size 1.27 1.27)
				)
			)
		)
		(duplicate_pad_numbers_are_jumpers no)
		(fp_line
			(start -0.7874 0.4064)
			(end -0.7874 -0.4064)
			(stroke
				(width 0.1524)
				(type default)
			)
			(layer "F.SilkS")
		)
		(fp_line
			(start 0.7874 0.4064)
			(end -0.7874 0.4064)
			(stroke
				(width 0.1524)
				(type default)
			)
			(layer "F.SilkS")
		)
		(fp_line
			(start -0.7874 -0.4064)
			(end 0.7874 -0.4064)
			(stroke
				(width 0.1524)
				(type default)
			)
			(layer "F.SilkS")
		)
		(fp_line
			(start 0.7874 -0.4064)
			(end 0.7874 0.4064)
			(stroke
				(width 0.1524)
				(type default)
			)
			(layer "F.SilkS")
		)
		(fp_line
			(start -0.67945 0.3048)
			(end -0.67945 -0.305054)
			(stroke
				(width 0.1)
				(type default)
			)
			(layer "F.Fab")
		)
		(fp_line
			(start -0.12065 0.3048)
			(end -0.67945 0.3048)
			(stroke
				(width 0.1)
				(type default)
			)
			(layer "F.Fab")
		)
		(fp_line
			(start 0.120396 0.3048)
			(end 0.120396 0.2794)
			(stroke
				(width 0.1)
				(type default)
			)
			(layer "F.Fab")
		)
		(fp_line
			(start 0.67945 0.3048)
			(end 0.120396 0.3048)
			(stroke
				(width 0.1)
				(type default)
			)
			(layer "F.Fab")
		)
		(fp_line
			(start -0.12065 0.2794)
			(end -0.12065 0.3048)
			(stroke
				(width 0.1)
				(type default)
			)
			(layer "F.Fab")
		)
		(fp_line
			(start 0.120396 0.2794)
			(end -0.12065 0.2794)
			(stroke
				(width 0.1)
				(type default)
			)
			(layer "F.Fab")
		)
		(fp_line
			(start -0.12065 -0.2794)
			(end 0.12065 -0.2794)
			(stroke
				(width 0.1)
				(type default)
			)
			(layer "F.Fab")
		)
		(fp_line
			(start 0.12065 -0.2794)
			(end 0.12065 -0.3048)
			(stroke
				(width 0.1)
				(type default)
			)
			(layer "F.Fab")
		)
		(fp_line
			(start 0.12065 -0.3048)
			(end 0.67945 -0.3048)
			(stroke
				(width 0.1)
				(type default)
			)
			(layer "F.Fab")
		)
		(fp_line
			(start 0.67945 -0.3048)
			(end 0.67945 0.3048)
			(stroke
				(width 0.1)
				(type default)
			)
			(layer "F.Fab")
		)
		(fp_line
			(start -0.67945 -0.305054)
			(end -0.12065 -0.305054)
			(stroke
				(width 0.1)
				(type default)
			)
			(layer "F.Fab")
		)
		(fp_line
			(start -0.12065 -0.305054)
			(end -0.12065 -0.2794)
			(stroke
				(width 0.1)
				(type default)
			)
			(layer "F.Fab")
		)
		(pad "1" smd circle
			(at -0.40005 0 270)
			(size 0 0)
			(layers "F.Cu" "F.Mask" "F.Paste")
			(net "P3V3_AUX")
		)
		(pad "2" smd circle
			(at 0.40005 0 270)
			(size 0 0)
			(layers "F.Cu" "F.Mask" "F.Paste")
			(net "SGPIO_SCM_INTR_N")
		)
	)
	(footprint ""
		(layer "F.Cu")
		(at 330.96962 -397.726154 180)
		(property "Reference" "R1369"
			(at 0 0 180)
			(layer "F.SilkS")
			(hide yes)
			(effects
				(font
					(size 1.27 1.27)
				)
			)
		)
		(property "Value" ""
			(at 0 0 180)
			(layer "F.Fab")
			(effects
				(font
					(size 1.27 1.27)
				)
			)
		)
		(duplicate_pad_numbers_are_jumpers no)
		(fp_line
			(start 0.32512 0.175006)
			(end -0.32512 0.175006)
			(stroke
				(width 0.1)
				(type default)
			)
			(layer "F.Fab")
		)
		(fp_line
			(start 0.32512 -0.175006)
			(end 0.32512 0.175006)
			(stroke
				(width 0.1)
				(type default)
			)
			(layer "F.Fab")
		)
		(fp_line
			(start -0.32512 0.175006)
			(end -0.32512 -0.175006)
			(stroke
				(width 0.1)
				(type default)
			)
			(layer "F.Fab")
		)
		(fp_line
			(start -0.32512 -0.175006)
			(end 0.32512 -0.175006)
			(stroke
				(width 0.1)
				(type default)
			)
			(layer "F.Fab")
		)
		(pad "1" smd rect
			(at -0.2667 0 180)
			(size 0.3048 0.381)
			(layers "F.Cu" "F.Mask" "F.Paste")
			(net "P1V8_CPU0_RT_1D")
		)
		(pad "2" smd rect
			(at 0.2667 0)
			(size 0.3048 0.381)
			(layers "F.Cu" "F.Mask" "F.Paste")
			(net "RXDET_BYP_RT_CPU0_P0")
		)
	)
	(footprint ""
		(layer "F.Cu")
		(at 302.133 -354.711 180)
		(property "Reference" "PR40"
			(at 0 0 180)
			(layer "F.SilkS")
			(hide yes)
			(effects
				(font
					(size 1.27 1.27)
				)
			)
		)
		(property "Value" ""
			(at 0 0 180)
			(layer "F.Fab")
			(effects
				(font
					(size 1.27 1.27)
				)
			)
		)
		(duplicate_pad_numbers_are_jumpers no)
		(fp_line
			(start 0.7874 0.4064)
			(end -0.7874 0.4064)
			(stroke
				(width 0.1524)
				(type default)
			)
			(layer "F.SilkS")
		)
		(fp_line
			(start 0.7874 -0.4064)
			(end 0.7874 0.4064)
			(stroke
				(width 0.1524)
				(type default)
			)
			(layer "F.SilkS")
		)
		(fp_line
			(start -0.7874 0.4064)
			(end -0.7874 -0.4064)
			(stroke
				(width 0.1524)
				(type default)
			)
			(layer "F.SilkS")
		)
		(fp_line
			(start -0.7874 -0.4064)
			(end 0.7874 -0.4064)
			(stroke
				(width 0.1524)
				(type default)
			)
			(layer "F.SilkS")
		)
		(fp_line
			(start 0.67945 0.3048)
			(end 0.120396 0.3048)
			(stroke
				(width 0.1)
				(type default)
			)
			(layer "F.Fab")
		)
		(fp_line
			(start 0.67945 -0.3048)
			(end 0.67945 0.3048)
			(stroke
				(width 0.1)
				(type default)
			)
			(layer "F.Fab")
		)
		(fp_line
			(start 0.12065 -0.2794)
			(end 0.12065 -0.3048)
			(stroke
				(width 0.1)
				(type default)
			)
			(layer "F.Fab")
		)
		(fp_line
			(start 0.12065 -0.3048)
			(end 0.67945 -0.3048)
			(stroke
				(width 0.1)
				(type default)
			)
			(layer "F.Fab")
		)
		(fp_line
			(start 0.120396 0.3048)
			(end 0.120396 0.2794)
			(stroke
				(width 0.1)
				(type default)
			)
			(layer "F.Fab")
		)
		(fp_line
			(start 0.120396 0.2794)
			(end -0.12065 0.2794)
			(stroke
				(width 0.1)
				(type default)
			)
			(layer "F.Fab")
		)
		(fp_line
			(start -0.12065 0.3048)
			(end -0.67945 0.3048)
			(stroke
				(width 0.1)
				(type default)
			)
			(layer "F.Fab")
		)
		(fp_line
			(start -0.12065 0.2794)
			(end -0.12065 0.3048)
			(stroke
				(width 0.1)
				(type default)
			)
			(layer "F.Fab")
		)
		(fp_line
			(start -0.12065 -0.2794)
			(end 0.12065 -0.2794)
			(stroke
				(width 0.1)
				(type default)
			)
			(layer "F.Fab")
		)
		(fp_line
			(start -0.12065 -0.305054)
			(end -0.12065 -0.2794)
			(stroke
				(width 0.1)
				(type default)
			)
			(layer "F.Fab")
		)
		(fp_line
			(start -0.67945 0.3048)
			(end -0.67945 -0.305054)
			(stroke
				(width 0.1)
				(type default)
			)
			(layer "F.Fab")
		)
		(fp_line
			(start -0.67945 -0.305054)
			(end -0.12065 -0.305054)
			(stroke
				(width 0.1)
				(type default)
			)
			(layer "F.Fab")
		)
		(pad "1" smd circle
			(at -0.40005 0 180)
			(size 0 0)
			(layers "F.Cu" "F.Mask" "F.Paste")
			(net "SVID_PVDDCR_CPU1_P0_SVTI")
		)
		(pad "2" smd circle
			(at 0.40005 0 180)
			(size 0 0)
			(layers "F.Cu" "F.Mask" "F.Paste")
			(net "GND")
		)
	)
)
